# SCM (Grand Teton) — schematic netlist excerpt (pin names and nets, part order shuffled) for the footprints in the layout excerpt that follows; sources: Cadence DE-HDL packaged netlist, KiCad conversion of 12092022_DA0F0TMDCD0_F0T_Management_Board_D_brd_V3_OCP.brd

R721  Q_RES  0 5% CHIP  pkg 0402LF  page 28 : A = FM_SLPS3_GF_N ; B = FM_SLPS3_GF_R2_N
R41  Q_RES  10K 1% EMPTY  pkg 0402LF  page 11 : A = P3V3_AUX ; B = LPC_ESPI_SEL

(kicad_pcb
	(version 20260206)
	(generator "pcbnew")
	(generator_version "10.0")
	(general
		(thickness 1.6)
		(legacy_teardrops no)
	)
	(paper "A4")
	(title_block
		(title "12092022_DA0F0TMDCD0_F0T_Management_Board_D_brd_V3_OCP.brd")
		(comment 1 "Grand Teton / footprints 1245-1246 of 1440")
	)
	(layers
		(0 "F.Cu" signal "TOP")
		(4 "In1.Cu" signal "GND")
		(6 "In2.Cu" signal "IN1")
		(8 "In3.Cu" signal "GND1")
		(10 "In4.Cu" signal "IN2")
		(12 "In5.Cu" signal "VCC")
		(14 "In6.Cu" signal "VCC1")
		(16 "In7.Cu" signal "IN3")
		(18 "In8.Cu" signal "GND2")
		(20 "In9.Cu" signal "IN4")
		(22 "In10.Cu" signal "GND3")
		(2 "B.Cu" signal "BOTTOM")
		(9 "F.Adhes" user "F.Adhesive")
		(11 "B.Adhes" user "B.Adhesive")
		(13 "F.Paste" user "Package Geometry/Pastemask Top")
		(15 "B.Paste" user "Package Geometry/Pastemask Bottom")
		(5 "F.SilkS" user "Ref Des/Silkscreen Top")
		(7 "B.SilkS" user "Ref Des/Silkscreen Bottom")
		(1 "F.Mask" user "Board Geometry/Soldermask Top")
		(3 "B.Mask" user "Board Geometry/Soldermask Bottom")
		(17 "Dwgs.User" user "User.Drawings")
		(19 "Cmts.User" user "User.Comments")
		(21 "Eco1.User" user "User.Eco1")
		(23 "Eco2.User" user "User.Eco2")
		(25 "Edge.Cuts" user "Board Geometry/Outline")
		(27 "Margin" user)
		(31 "F.CrtYd" user "Package Geometry/Place Bound Top")
		(29 "B.CrtYd" user "Package Geometry/Place Bound Bottom")
		(35 "F.Fab" user "Ref Des/Assembly Top")
		(33 "B.Fab" user "Ref Des/Assembly Bottom")
	)
	(footprint ""
		(layer "B.Cu")
		(at 54.8132 -107.0102 -90)
		(property "Reference" "R41"
			(at 0 0 90)
			(layer "B.SilkS")
			(hide yes)
			(effects
				(font
					(size 1.27 1.27)
				)
				(justify mirror)
			)
		)
		(property "Value" ""
			(at 0 0 90)
			(layer "B.Fab")
			(effects
				(font
					(size 1.27 1.27)
				)
				(justify mirror)
			)
		)
		(duplicate_pad_numbers_are_jumpers no)
		(fp_line
			(start -0.7874 0.4064)
			(end 0.7874 0.4064)
			(stroke
				(width 0.1524)
				(type default)
			)
			(layer "B.SilkS")
		)
		(fp_line
			(start 0.7874 0.4064)
			(end 0.7874 -0.4064)
			(stroke
				(width 0.1524)
				(type default)
			)
			(layer "B.SilkS")
		)
		(fp_line
			(start -0.7874 -0.4064)
			(end -0.7874 0.4064)
			(stroke
				(width 0.1524)
				(type default)
			)
			(layer "B.SilkS")
		)
		(fp_line
			(start 0.7874 -0.4064)
			(end -0.7874 -0.4064)
			(stroke
				(width 0.1524)
				(type default)
			)
			(layer "B.SilkS")
		)
		(fp_line
			(start -0.67945 0.3048)
			(end -0.120396 0.3048)
			(stroke
				(width 0.1)
				(type default)
			)
			(layer "B.Fab")
		)
		(fp_line
			(start -0.120396 0.3048)
			(end -0.120396 0.2794)
			(stroke
				(width 0.1)
				(type default)
			)
			(layer "B.Fab")
		)
		(fp_line
			(start 0.12065 0.3048)
			(end 0.67945 0.3048)
			(stroke
				(width 0.1)
				(type default)
			)
			(layer "B.Fab")
		)
		(fp_line
			(start 0.67945 0.3048)
			(end 0.67945 -0.305054)
			(stroke
				(width 0.1)
				(type default)
			)
			(layer "B.Fab")
		)
		(fp_line
			(start -0.120396 0.2794)
			(end 0.12065 0.2794)
			(stroke
				(width 0.1)
				(type default)
			)
			(layer "B.Fab")
		)
		(fp_line
			(start 0.12065 0.2794)
			(end 0.12065 0.3048)
			(stroke
				(width 0.1)
				(type default)
			)
			(layer "B.Fab")
		)
		(fp_line
			(start -0.12065 -0.2794)
			(end -0.12065 -0.3048)
			(stroke
				(width 0.1)
				(type default)
			)
			(layer "B.Fab")
		)
		(fp_line
			(start 0.12065 -0.2794)
			(end -0.12065 -0.2794)
			(stroke
				(width 0.1)
				(type default)
			)
			(layer "B.Fab")
		)
		(fp_line
			(start -0.67945 -0.3048)
			(end -0.67945 0.3048)
			(stroke
				(width 0.1)
				(type default)
			)
			(layer "B.Fab")
		)
		(fp_line
			(start -0.12065 -0.3048)
			(end -0.67945 -0.3048)
			(stroke
				(width 0.1)
				(type default)
			)
			(layer "B.Fab")
		)
		(fp_line
			(start 0.12065 -0.305054)
			(end 0.12065 -0.2794)
			(stroke
				(width 0.1)
				(type default)
			)
			(layer "B.Fab")
		)
		(fp_line
			(start 0.67945 -0.305054)
			(end 0.12065 -0.305054)
			(stroke
				(width 0.1)
				(type default)
			)
			(layer "B.Fab")
		)
		(pad "1" smd circle
			(at 0.40005 0 90)
			(size 0 0)
			(layers "B.Cu" "B.Mask" "B.Paste")
			(net "P3V3_AUX")
		)
		(pad "2" smd circle
			(at -0.40005 0 90)
			(size 0 0)
			(layers "B.Cu" "B.Mask" "B.Paste")
			(net "LPC_ESPI_SEL")
		)
	)
	(footprint ""
		(layer "B.Cu")
		(at 51.2445 -90.4875 180)
		(property "Reference" "R721"
			(at 0 0 0)
			(layer "B.SilkS")
			(hide yes)
			(effects
				(font
					(size 1.27 1.27)
				)
				(justify mirror)
			)
		)
		(property "Value" ""
			(at 0 0 0)
			(layer "B.Fab")
			(effects
				(font
					(size 1.27 1.27)
				)
				(justify mirror)
			)
		)
		(duplicate_pad_numbers_are_jumpers no)
		(fp_line
			(start 0.7874 0.4064)
			(end 0.7874 -0.4064)
			(stroke
				(width 0.1524)
				(type default)
			)
			(layer "B.SilkS")
		)
		(fp_line
			(start 0.7874 -0.4064)
			(end -0.7874 -0.4064)
			(stroke
				(width 0.1524)
				(type default)
			)
			(layer "B.SilkS")
		)
		(fp_line
			(start -0.7874 0.4064)
			(end 0.7874 0.4064)
			(stroke
				(width 0.1524)
				(type default)
			)
			(layer "B.SilkS")
		)
		(fp_line
			(start -0.7874 -0.4064)
			(end -0.7874 0.4064)
			(stroke
				(width 0.1524)
				(type default)
			)
			(layer "B.SilkS")
		)
		(fp_line
			(start 0.67945 0.3048)
			(end 0.67945 -0.305054)
			(stroke
				(width 0.1)
				(type default)
			)
			(layer "B.Fab")
		)
		(fp_line
			(start 0.67945 -0.305054)
			(end 0.12065 -0.305054)
			(stroke
				(width 0.1)
				(type default)
			)
			(layer "B.Fab")
		)
		(fp_line
			(start 0.12065 0.3048)
			(end 0.67945 0.3048)
			(stroke
				(width 0.1)
				(type default)
			)
			(layer "B.Fab")
		)
		(fp_line
			(start 0.12065 0.2794)
			(end 0.12065 0.3048)
			(stroke
				(width 0.1)
				(type default)
			)
			(layer "B.Fab")
		)
		(fp_line
			(start 0.12065 -0.2794)
			(end -0.12065 -0.2794)
			(stroke
				(width 0.1)
				(type default)
			)
			(layer "B.Fab")
		)
		(fp_line
			(start 0.12065 -0.305054)
			(end 0.12065 -0.2794)
			(stroke
				(width 0.1)
				(type default)
			)
			(layer "B.Fab")
		)
		(fp_line
			(start -0.120396 0.3048)
			(end -0.120396 0.2794)
			(stroke
				(width 0.1)
				(type default)
			)
			(layer "B.Fab")
		)
		(fp_line
			(start -0.120396 0.2794)
			(end 0.12065 0.2794)
			(stroke
				(width 0.1)
				(type default)
			)
			(layer "B.Fab")
		)
		(fp_line
			(start -0.12065 -0.2794)
			(end -0.12065 -0.3048)
			(stroke
				(width 0.1)
				(type default)
			)
			(layer "B.Fab")
		)
		(fp_line
			(start -0.12065 -0.3048)
			(end -0.67945 -0.3048)
			(stroke
				(width 0.1)
				(type default)
			)
			(layer "B.Fab")
		)
		(fp_line
			(start -0.67945 0.3048)
			(end -0.120396 0.3048)
			(stroke
				(width 0.1)
				(type default)
			)
			(layer "B.Fab")
		)
		(fp_line
			(start -0.67945 -0.3048)
			(end -0.67945 0.3048)
			(stroke
				(width 0.1)
				(type default)
			)
			(layer "B.Fab")
		)
		(pad "1" smd circle
			(at 0.40005 0)
			(size 0 0)
			(layers "B.Cu" "B.Mask" "B.Paste")
			(net "FM_SLPS3_GF_N")
		)
		(pad "2" smd circle
			(at -0.40005 0)
			(size 0 0)
			(layers "B.Cu" "B.Mask" "B.Paste")
			(net "FM_SLPS3_GF_R2_N")
		)
	)
)
